(kicad_pcb
	(version 20260206)
	(generator "pcbnew")
	(generator_version "10.0")
	(general
		(thickness 1.6)
		(legacy_teardrops no)
	)
	(paper "A4")
	(title_block
		(title "03242023_DA0F0TMBIJ0_F0T_Motherboard_J_brd_V01_OCP.brd")
		(comment 1 "Grand Teton / footprint 1682 of 6105 (U1), pads 3349-3460 of 4677")
	)
	(layers
		(0 "F.Cu" signal "TOP")
		(4 "In1.Cu" signal "GND")
		(6 "In2.Cu" signal "IN1")
		(8 "In3.Cu" signal "GND1")
		(10 "In4.Cu" signal "IN2")
		(12 "In5.Cu" signal "GND2")
		(14 "In6.Cu" signal "IN3")
		(16 "In7.Cu" signal "GND3")
		(18 "In8.Cu" signal "VCC")
		(20 "In9.Cu" signal "VCC1")
		(22 "In10.Cu" signal "GND4")
		(24 "In11.Cu" signal "IN4")
		(26 "In12.Cu" signal "GND5")
		(28 "In13.Cu" signal "IN5")
		(30 "In14.Cu" signal "GND6")
		(32 "In15.Cu" signal "IN6")
		(34 "In16.Cu" signal "GND7")
		(2 "B.Cu" signal "BOTTOM")
		(9 "F.Adhes" user "F.Adhesive")
		(11 "B.Adhes" user "B.Adhesive")
		(13 "F.Paste" user "Package Geometry/Pastemask Top")
		(15 "B.Paste" user "Package Geometry/Pastemask Bottom")
		(5 "F.SilkS" user "Ref Des/Silkscreen Top")
		(7 "B.SilkS" user "Ref Des/Silkscreen Bottom")
		(1 "F.Mask" user "Board Geometry/Soldermask Top")
		(3 "B.Mask" user "Board Geometry/Soldermask Bottom")
		(17 "Dwgs.User" user "User.Drawings")
		(19 "Cmts.User" user "User.Comments")
		(21 "Eco1.User" user "User.Eco1")
		(23 "Eco2.User" user "User.Eco2")
		(25 "Edge.Cuts" user "Board Geometry/Outline")
		(27 "Margin" user)
		(31 "F.CrtYd" user "Package Geometry/Place Bound Top")
		(29 "B.CrtYd" user "Package Geometry/Place Bound Bottom")
		(35 "F.Fab" user "Ref Des/Assembly Top")
		(33 "B.Fab" user "Ref Des/Assembly Bottom")
	)
	(footprint ""
		(layer "F.Cu")
		(at 111.93018 -251.76988 90)
		(property "Reference" "U1"
			(at -74.913236 41.548812 0)
			(unlocked yes)
			(layer "F.SilkS")
			(effects
				(font
					(size 1.6002 1.1938)
					(thickness 0.1524)
				)
				(justify left)
			)
		)
		(property "Value" ""
			(at 0 0 90)
			(layer "F.Fab")
			(effects
				(font
					(size 1.27 1.27)
				)
			)
		)
		(duplicate_pad_numbers_are_jumpers no)
		(pad "EA33" smd circle
			(at -11.380724 19.915886 270)
			(size 0.4318 0.4318)
			(layers "F.Cu" "F.Mask" "F.Paste")
			(net "GND")
		)
		(pad "EA35" smd circle
			(at -9.752838 19.915886 270)
			(size 0.4318 0.4318)
			(layers "F.Cu" "F.Mask" "F.Paste")
			(net "M_G_CPU1_SB_CB<2>")
		)
		(pad "EA37" smd circle
			(at -8.124952 19.915886 270)
			(size 0.4318 0.4318)
			(layers "F.Cu" "F.Mask" "F.Paste")
			(net "M_G_CPU1_SB_CB<7>")
		)
		(pad "EA39" smd circle
			(at -6.49732 19.915886 270)
			(size 0.4318 0.4318)
			(layers "F.Cu" "F.Mask" "F.Paste")
			(net "GND")
		)
		(pad "EA41" smd circle
			(at -4.869434 19.915886 270)
			(size 0.4318 0.4318)
			(layers "F.Cu" "F.Mask" "F.Paste")
			(net "M_G_CPU1_SB_CS_N<0>")
		)
		(pad "EA43" smd circle
			(at -3.241802 19.915886 270)
			(size 0.4318 0.4318)
			(layers "F.Cu" "F.Mask" "F.Paste")
			(net "M_G_CPU1_SB_CA<5>")
		)
		(pad "EA45" smd circle
			(at -1.613916 19.915886 270)
			(size 0.4318 0.4318)
			(layers "F.Cu" "F.Mask" "F.Paste")
			(net "GND")
		)
		(pad "EA48" smd circle
			(at 2.427732 20.025868 270)
			(size 0.4318 0.4318)
			(layers "F.Cu" "F.Mask" "F.Paste")
			(net "M_G_CPU1_SA_RSP<0>")
		)
		(pad "EA50" smd circle
			(at 4.055618 20.025868 270)
			(size 0.4318 0.4318)
			(layers "F.Cu" "F.Mask" "F.Paste")
			(net "M_F_CPU1_SA_PAR")
		)
		(pad "EA52" smd circle
			(at 5.68325 20.025868 270)
			(size 0.4318 0.4318)
			(layers "F.Cu" "F.Mask" "F.Paste")
			(net "GND")
		)
		(pad "EA54" smd circle
			(at 7.311136 20.025868 270)
			(size 0.4318 0.4318)
			(layers "F.Cu" "F.Mask" "F.Paste")
			(net "M_F_CPU1_SA_DQ<30>")
		)
		(pad "EA56" smd circle
			(at 8.939022 20.025868 270)
			(size 0.4318 0.4318)
			(layers "F.Cu" "F.Mask" "F.Paste")
			(net "M_F_CPU1_SA_DQ<27>")
		)
		(pad "EA58" smd circle
			(at 10.566654 20.025868 270)
			(size 0.4318 0.4318)
			(layers "F.Cu" "F.Mask" "F.Paste")
			(net "GND")
		)
		(pad "EA60" smd circle
			(at 12.19454 20.025868 270)
			(size 0.4318 0.4318)
			(layers "F.Cu" "F.Mask" "F.Paste")
			(net "M_G_CPU1_SA_DQ<22>")
		)
		(pad "EA62" smd circle
			(at 13.822426 20.025868 270)
			(size 0.4318 0.4318)
			(layers "F.Cu" "F.Mask" "F.Paste")
			(net "M_G_CPU1_SA_DQ<19>")
		)
		(pad "EA64" smd circle
			(at 15.450058 20.025868 270)
			(size 0.4318 0.4318)
			(layers "F.Cu" "F.Mask" "F.Paste")
			(net "GND")
		)
		(pad "EA66" smd circle
			(at 17.07769 20.025868 270)
			(size 0.4318 0.4318)
			(layers "F.Cu" "F.Mask" "F.Paste")
			(net "M_F_CPU1_SA_DQ<14>")
		)
		(pad "EA68" smd circle
			(at 18.705576 20.025868 270)
			(size 0.4318 0.4318)
			(layers "F.Cu" "F.Mask" "F.Paste")
			(net "M_F_CPU1_SA_DQ<11>")
		)
		(pad "EA70" smd circle
			(at 20.333462 20.025868 270)
			(size 0.4318 0.4318)
			(layers "F.Cu" "F.Mask" "F.Paste")
			(net "GND")
		)
		(pad "EA72" smd circle
			(at 21.961094 20.025868 270)
			(size 0.4318 0.4318)
			(layers "F.Cu" "F.Mask" "F.Paste")
			(net "M_G_CPU1_SA_DQ<6>")
		)
		(pad "EA74" smd circle
			(at 23.58898 20.025868 270)
			(size 0.4318 0.4318)
			(layers "F.Cu" "F.Mask" "F.Paste")
			(net "M_G_CPU1_SA_DQ<3>")
		)
		(pad "EA76" smd circle
			(at 25.216612 20.025868 270)
			(size 0.4318 0.4318)
			(layers "F.Cu" "F.Mask" "F.Paste")
			(net "GND")
		)
		(pad "EA78" smd circle
			(at 26.844498 20.025868 270)
			(size 0.4318 0.4318)
			(layers "F.Cu" "F.Mask" "F.Paste")
			(net "GND")
		)
		(pad "EA80" smd circle
			(at 28.472384 20.025868 270)
			(size 0.4318 0.4318)
			(layers "F.Cu" "F.Mask" "F.Paste")
			(net "GND")
		)
		(pad "EA82" smd circle
			(at 30.100016 20.025868 270)
			(size 0.4318 0.4318)
			(layers "F.Cu" "F.Mask" "F.Paste")
			(net "GND")
		)
		(pad "EA84" smd circle
			(at 31.727902 20.025868 270)
			(size 0.4318 0.4318)
			(layers "F.Cu" "F.Mask" "F.Paste")
			(net "GND")
		)
		(pad "EA86" smd circle
			(at 33.355534 20.025868 270)
			(size 0.4318 0.4318)
			(layers "F.Cu" "F.Mask" "F.Paste")
			(net "P5E_CPU1_PE3_TX_DP<2>")
		)
		(pad "EA88" smd circle
			(at 34.98342 20.025868 270)
			(size 0.4318 0.4318)
			(layers "F.Cu" "F.Mask" "F.Paste")
			(net "GND")
		)
		(pad "EA90" smd circle
			(at 36.611306 20.025868 270)
			(size 0.4318 0.4318)
			(layers "F.Cu" "F.Mask" "F.Paste")
			(net "P5E_CPU1_PE3_RX_DP<3>")
		)
		(pad "EB2" smd circle
			(at -36.611306 20.385532 270)
			(size 0.4318 0.4318)
			(layers "F.Cu" "F.Mask" "F.Paste")
			(net "UPI_CPU0_CPU1_P0P1_DP<3>")
		)
		(pad "EB4" smd circle
			(at -34.98342 20.385532 270)
			(size 0.4318 0.4318)
			(layers "F.Cu" "F.Mask" "F.Paste")
			(net "GND")
		)
		(pad "EB6" smd circle
			(at -33.355534 20.385532 270)
			(size 0.4318 0.4318)
			(layers "F.Cu" "F.Mask" "F.Paste")
			(net "UPI_CPU1_CPU0_P1P0_DN<2>")
		)
		(pad "EB8" smd circle
			(at -31.727902 20.385532 270)
			(size 0.4318 0.4318)
			(layers "F.Cu" "F.Mask" "F.Paste")
			(net "GND")
		)
		(pad "EB10" smd circle
			(at -30.100016 20.385532 270)
			(size 0.4318 0.4318)
			(layers "F.Cu" "F.Mask" "F.Paste")
			(net "P5E_CPU1_PE2_RX_DP<12>")
		)
		(pad "EB12" smd circle
			(at -28.472384 20.385532 270)
			(size 0.4318 0.4318)
			(layers "F.Cu" "F.Mask" "F.Paste")
			(net "GND")
		)
		(pad "EB14" smd circle
			(at -26.844498 20.385532 270)
			(size 0.4318 0.4318)
			(layers "F.Cu" "F.Mask" "F.Paste")
			(net "P5E_CPU1_PE2_TX_DN<13>")
		)
		(pad "EB16" smd circle
			(at -25.216612 20.385532 270)
			(size 0.4318 0.4318)
			(layers "F.Cu" "F.Mask" "F.Paste")
			(net "GND")
		)
		(pad "EB18" smd circle
			(at -23.58898 20.385532 270)
			(size 0.4318 0.4318)
			(layers "F.Cu" "F.Mask" "F.Paste")
			(net "M_F_CPU1_SB_DQS_DP<8>")
		)
		(pad "EB20" smd circle
			(at -21.961094 20.385532 270)
			(size 0.4318 0.4318)
			(layers "F.Cu" "F.Mask" "F.Paste")
			(net "GND")
		)
		(pad "EB22" smd circle
			(at -20.333462 20.385532 270)
			(size 0.4318 0.4318)
			(layers "F.Cu" "F.Mask" "F.Paste")
			(net "GND")
		)
		(pad "EB24" smd circle
			(at -18.705576 20.385532 270)
			(size 0.4318 0.4318)
			(layers "F.Cu" "F.Mask" "F.Paste")
			(net "M_G_CPU1_SB_DQS_DN<7>")
		)
		(pad "EB26" smd circle
			(at -17.07769 20.385532 270)
			(size 0.4318 0.4318)
			(layers "F.Cu" "F.Mask" "F.Paste")
			(net "GND")
		)
		(pad "EB28" smd circle
			(at -15.450058 20.385532 270)
			(size 0.4318 0.4318)
			(layers "F.Cu" "F.Mask" "F.Paste")
			(net "GND")
		)
		(pad "EB30" smd circle
			(at -13.822426 20.385532 270)
			(size 0.4318 0.4318)
			(layers "F.Cu" "F.Mask" "F.Paste")
			(net "M_F_CPU1_SB_DQS_DN<5>")
		)
		(pad "EB32" smd circle
			(at -12.19454 20.385532 270)
			(size 0.4318 0.4318)
			(layers "F.Cu" "F.Mask" "F.Paste")
			(net "GND")
		)
		(pad "EB34" smd circle
			(at -10.566654 20.385532 270)
			(size 0.4318 0.4318)
			(layers "F.Cu" "F.Mask" "F.Paste")
			(net "GND")
		)
		(pad "EB36" smd circle
			(at -8.939022 20.385532 270)
			(size 0.4318 0.4318)
			(layers "F.Cu" "F.Mask" "F.Paste")
			(net "M_G_CPU1_SB_DQS_DN<4>")
		)
		(pad "EB38" smd circle
			(at -7.311136 20.385532 270)
			(size 0.4318 0.4318)
			(layers "F.Cu" "F.Mask" "F.Paste")
			(net "GND")
		)
		(pad "EB40" smd circle
			(at -5.68325 20.385532 270)
			(size 0.4318 0.4318)
			(layers "F.Cu" "F.Mask" "F.Paste")
			(net "GND")
		)
		(pad "EB42" smd circle
			(at -4.055618 20.385532 270)
			(size 0.4318 0.4318)
			(layers "F.Cu" "F.Mask" "F.Paste")
			(net "M_G_CPU1_SB_PAR")
		)
		(pad "EB44" smd circle
			(at -2.427732 20.385532 270)
			(size 0.4318 0.4318)
			(layers "F.Cu" "F.Mask" "F.Paste")
			(net "GND")
		)
		(pad "EB47" smd circle
			(at 1.613916 20.495514 270)
			(size 0.4318 0.4318)
			(layers "F.Cu" "F.Mask" "F.Paste")
			(net "GND")
		)
		(pad "EB49" smd circle
			(at 3.241802 20.495514 270)
			(size 0.4318 0.4318)
			(layers "F.Cu" "F.Mask" "F.Paste")
			(net "M_F_CPU1_CLK_DP<0>")
		)
		(pad "EB51" smd circle
			(at 4.869434 20.495514 270)
			(size 0.4318 0.4318)
			(layers "F.Cu" "F.Mask" "F.Paste")
			(net "GND")
		)
		(pad "EB53" smd circle
			(at 6.49732 20.495514 270)
			(size 0.4318 0.4318)
			(layers "F.Cu" "F.Mask" "F.Paste")
			(net "GND")
		)
		(pad "EB55" smd circle
			(at 8.124952 20.495514 270)
			(size 0.4318 0.4318)
			(layers "F.Cu" "F.Mask" "F.Paste")
			(net "M_F_CPU1_SA_DQS_DN<8>")
		)
		(pad "EB57" smd circle
			(at 9.752838 20.495514 270)
			(size 0.4318 0.4318)
			(layers "F.Cu" "F.Mask" "F.Paste")
			(net "GND")
		)
		(pad "EB59" smd circle
			(at 11.380724 20.495514 270)
			(size 0.4318 0.4318)
			(layers "F.Cu" "F.Mask" "F.Paste")
			(net "GND")
		)
		(pad "EB61" smd circle
			(at 13.008356 20.495514 270)
			(size 0.4318 0.4318)
			(layers "F.Cu" "F.Mask" "F.Paste")
			(net "M_G_CPU1_SA_DQS_DN<7>")
		)
		(pad "EB63" smd circle
			(at 14.635988 20.495514 270)
			(size 0.4318 0.4318)
			(layers "F.Cu" "F.Mask" "F.Paste")
			(net "GND")
		)
		(pad "EB65" smd circle
			(at 16.263874 20.495514 270)
			(size 0.4318 0.4318)
			(layers "F.Cu" "F.Mask" "F.Paste")
			(net "GND")
		)
		(pad "EB67" smd circle
			(at 17.89176 20.495514 270)
			(size 0.4318 0.4318)
			(layers "F.Cu" "F.Mask" "F.Paste")
			(net "M_F_CPU1_SA_DQS_DN<6>")
		)
		(pad "EB69" smd circle
			(at 19.519392 20.495514 270)
			(size 0.4318 0.4318)
			(layers "F.Cu" "F.Mask" "F.Paste")
			(net "GND")
		)
		(pad "EB71" smd circle
			(at 21.147278 20.495514 270)
			(size 0.4318 0.4318)
			(layers "F.Cu" "F.Mask" "F.Paste")
			(net "GND")
		)
		(pad "EB73" smd circle
			(at 22.77491 20.495514 270)
			(size 0.4318 0.4318)
			(layers "F.Cu" "F.Mask" "F.Paste")
			(net "M_G_CPU1_SA_DQS_DN<5>")
		)
		(pad "EB75" smd circle
			(at 24.402796 20.495514 270)
			(size 0.4318 0.4318)
			(layers "F.Cu" "F.Mask" "F.Paste")
			(net "GND")
		)
		(pad "EB77" smd circle
			(at 26.030682 20.495514 270)
			(size 0.4318 0.4318)
			(layers "F.Cu" "F.Mask" "F.Paste")
			(net "M_F_CPU1_SA_DQ<0>")
		)
		(pad "EB79" smd circle
			(at 27.658314 20.495514 270)
			(size 0.4318 0.4318)
			(layers "F.Cu" "F.Mask" "F.Paste")
			(net "GND")
		)
		(pad "EB81" smd circle
			(at 29.2862 20.495514 270)
			(size 0.4318 0.4318)
			(layers "F.Cu" "F.Mask" "F.Paste")
			(net "GND")
		)
		(pad "EB83" smd circle
			(at 30.914086 20.495514 270)
			(size 0.4318 0.4318)
			(layers "F.Cu" "F.Mask" "F.Paste")
			(net "GND")
		)
		(pad "EB85" smd circle
			(at 32.541718 20.495514 270)
			(size 0.4318 0.4318)
			(layers "F.Cu" "F.Mask" "F.Paste")
			(net "P5E_CPU1_PE3_TX_DN<1>")
		)
		(pad "EB87" smd circle
			(at 34.169604 20.495514 270)
			(size 0.4318 0.4318)
			(layers "F.Cu" "F.Mask" "F.Paste")
			(net "GND")
		)
		(pad "EB89" smd circle
			(at 35.797236 20.495514 270)
			(size 0.4318 0.4318)
			(layers "F.Cu" "F.Mask" "F.Paste")
			(net "P5E_CPU1_PE3_RX_DP<2>")
		)
		(pad "EB91" smd oval
			(at 37.425122 20.495514)
			(size 0.381 0.4826)
			(drill
				(offset 0 -0.0508)
			)
			(layers "F.Cu" "F.Mask" "F.Paste")
			(net "GND")
		)
		(pad "EC1" smd oval
			(at -37.425122 20.855686 180)
			(size 0.381 0.4826)
			(drill
				(offset 0 -0.0508)
			)
			(layers "F.Cu" "F.Mask" "F.Paste")
			(net "GND")
		)
		(pad "EC3" smd circle
			(at -35.797236 20.855686 270)
			(size 0.4318 0.4318)
			(layers "F.Cu" "F.Mask" "F.Paste")
			(net "UPI_CPU0_CPU1_P0P1_DP<2>")
		)
		(pad "EC5" smd circle
			(at -34.169604 20.855686 270)
			(size 0.4318 0.4318)
			(layers "F.Cu" "F.Mask" "F.Paste")
			(net "GND")
		)
		(pad "EC7" smd circle
			(at -32.541718 20.855686 270)
			(size 0.4318 0.4318)
			(layers "F.Cu" "F.Mask" "F.Paste")
			(net "UPI_CPU1_CPU0_P1P0_DN<1>")
		)
		(pad "EC9" smd circle
			(at -30.914086 20.855686 270)
			(size 0.4318 0.4318)
			(layers "F.Cu" "F.Mask" "F.Paste")
			(net "GND")
		)
		(pad "EC11" smd circle
			(at -29.2862 20.855686 270)
			(size 0.4318 0.4318)
			(layers "F.Cu" "F.Mask" "F.Paste")
			(net "P5E_CPU1_PE2_RX_DP<13>")
		)
		(pad "EC13" smd circle
			(at -27.658314 20.855686 270)
			(size 0.4318 0.4318)
			(layers "F.Cu" "F.Mask" "F.Paste")
			(net "GND")
		)
		(pad "EC15" smd circle
			(at -26.030682 20.855686 270)
			(size 0.4318 0.4318)
			(layers "F.Cu" "F.Mask" "F.Paste")
			(net "P5E_CPU1_PE2_TX_DP<13>")
		)
		(pad "EC17" smd circle
			(at -24.402796 20.855686 270)
			(size 0.4318 0.4318)
			(layers "F.Cu" "F.Mask" "F.Paste")
			(net "M_F_CPU1_SB_DQ<30>")
		)
		(pad "EC19" smd circle
			(at -22.77491 20.855686 270)
			(size 0.4318 0.4318)
			(layers "F.Cu" "F.Mask" "F.Paste")
			(net "GND")
		)
		(pad "EC21" smd circle
			(at -21.147278 20.855686 270)
			(size 0.4318 0.4318)
			(layers "F.Cu" "F.Mask" "F.Paste")
			(net "M_F_CPU1_SB_DQS_DP<1>")
		)
		(pad "EC23" smd circle
			(at -19.519392 20.855686 270)
			(size 0.4318 0.4318)
			(layers "F.Cu" "F.Mask" "F.Paste")
			(net "GND")
		)
		(pad "EC25" smd circle
			(at -17.89176 20.855686 270)
			(size 0.4318 0.4318)
			(layers "F.Cu" "F.Mask" "F.Paste")
			(net "GND")
		)
		(pad "EC27" smd circle
			(at -16.263874 20.855686 270)
			(size 0.4318 0.4318)
			(layers "F.Cu" "F.Mask" "F.Paste")
			(net "M_E_CPU1_SB_DQS_DP<0>")
		)
		(pad "EC29" smd circle
			(at -14.635988 20.855686 270)
			(size 0.4318 0.4318)
			(layers "F.Cu" "F.Mask" "F.Paste")
			(net "GND")
		)
		(pad "EC31" smd circle
			(at -13.008356 20.855686 270)
			(size 0.4318 0.4318)
			(layers "F.Cu" "F.Mask" "F.Paste")
			(net "GND")
		)
		(pad "EC33" smd circle
			(at -11.380724 20.855686 270)
			(size 0.4318 0.4318)
			(layers "F.Cu" "F.Mask" "F.Paste")
			(net "M_F_CPU1_SB_DQS_DP<9>")
		)
		(pad "EC35" smd circle
			(at -9.752838 20.855686 270)
			(size 0.4318 0.4318)
			(layers "F.Cu" "F.Mask" "F.Paste")
			(net "GND")
		)
		(pad "EC37" smd circle
			(at -8.124952 20.855686 270)
			(size 0.4318 0.4318)
			(layers "F.Cu" "F.Mask" "F.Paste")
			(net "GND")
		)
		(pad "EC39" smd circle
			(at -6.49732 20.855686 270)
			(size 0.4318 0.4318)
			(layers "F.Cu" "F.Mask" "F.Paste")
			(net "M_F_CPU1_SB_CA<6>")
		)
		(pad "EC41" smd circle
			(at -4.869434 20.855686 270)
			(size 0.4318 0.4318)
			(layers "F.Cu" "F.Mask" "F.Paste")
			(net "GND")
		)
		(pad "EC43" smd circle
			(at -3.241802 20.855686 270)
			(size 0.4318 0.4318)
			(layers "F.Cu" "F.Mask" "F.Paste")
			(net "GND")
		)
		(pad "EC45" smd circle
			(at -1.613916 20.855686 270)
			(size 0.4318 0.4318)
			(layers "F.Cu" "F.Mask" "F.Paste")
			(net "M_E_CPU1_CLK_DP<1>")
		)
		(pad "EC48" smd circle
			(at 2.427732 20.965668 270)
			(size 0.4318 0.4318)
			(layers "F.Cu" "F.Mask" "F.Paste")
			(net "GND")
		)
		(pad "EC50" smd circle
			(at 4.055618 20.965668 270)
			(size 0.4318 0.4318)
			(layers "F.Cu" "F.Mask" "F.Paste")
			(net "GND")
		)
		(pad "EC52" smd circle
			(at 5.68325 20.965668 270)
			(size 0.4318 0.4318)
			(layers "F.Cu" "F.Mask" "F.Paste")
			(net "M_F_CPU1_SA_CA<0>")
		)
		(pad "EC54" smd circle
			(at 7.311136 20.965668 270)
			(size 0.4318 0.4318)
			(layers "F.Cu" "F.Mask" "F.Paste")
			(net "GND")
		)
		(pad "EC56" smd circle
			(at 8.939022 20.965668 270)
			(size 0.4318 0.4318)
			(layers "F.Cu" "F.Mask" "F.Paste")
			(net "GND")
		)
		(pad "EC58" smd circle
			(at 10.566654 20.965668 270)
			(size 0.4318 0.4318)
			(layers "F.Cu" "F.Mask" "F.Paste")
			(net "M_F_CPU1_SA_DQS_DP<4>")
		)
		(pad "EC60" smd circle
			(at 12.19454 20.965668 270)
			(size 0.4318 0.4318)
			(layers "F.Cu" "F.Mask" "F.Paste")
			(net "GND")
		)
		(pad "EC62" smd circle
			(at 13.822426 20.965668 270)
			(size 0.4318 0.4318)
			(layers "F.Cu" "F.Mask" "F.Paste")
			(net "GND")
		)
		(pad "EC64" smd circle
			(at 15.450058 20.965668 270)
			(size 0.4318 0.4318)
			(layers "F.Cu" "F.Mask" "F.Paste")
			(net "M_F_CPU1_SA_DQS_DN<2>")
		)
		(pad "EC66" smd circle
			(at 17.07769 20.965668 270)
			(size 0.4318 0.4318)
			(layers "F.Cu" "F.Mask" "F.Paste")
			(net "GND")
		)
		(pad "EC68" smd circle
			(at 18.705576 20.965668 270)
			(size 0.4318 0.4318)
			(layers "F.Cu" "F.Mask" "F.Paste")
			(net "GND")
		)
		(pad "EC70" smd circle
			(at 20.333462 20.965668 270)
			(size 0.4318 0.4318)
			(layers "F.Cu" "F.Mask" "F.Paste")
			(net "M_E_CPU1_SA_DQS_DN<1>")
		)
		(pad "EC72" smd circle
			(at 21.961094 20.965668 270)
			(size 0.4318 0.4318)
			(layers "F.Cu" "F.Mask" "F.Paste")
			(net "GND")
		)
		(pad "EC74" smd circle
			(at 23.58898 20.965668 270)
			(size 0.4318 0.4318)
			(layers "F.Cu" "F.Mask" "F.Paste")
			(net "GND")
		)
		(pad "EC76" smd circle
			(at 25.216612 20.965668 270)
			(size 0.4318 0.4318)
			(layers "F.Cu" "F.Mask" "F.Paste")
			(net "M_F_CPU1_SA_DQS_DP<0>")
		)
	)
)
